(kicad_pcb
	(version 20260206)
	(generator "pcbnew")
	(generator_version "10.0")
	(general
		(thickness 1.6)
		(legacy_teardrops no)
	)
	(paper "A4")
	(title_block
		(title "12092022_DA0F0TMDCD0_F0T_Management_Board_D_brd_V3_OCP.brd")
		(comment 1 "Grand Teton / footprints 780-785 of 1440")
	)
	(layers
		(0 "F.Cu" signal "TOP")
		(4 "In1.Cu" signal "GND")
		(6 "In2.Cu" signal "IN1")
		(8 "In3.Cu" signal "GND1")
		(10 "In4.Cu" signal "IN2")
		(12 "In5.Cu" signal "VCC")
		(14 "In6.Cu" signal "VCC1")
		(16 "In7.Cu" signal "IN3")
		(18 "In8.Cu" signal "GND2")
		(20 "In9.Cu" signal "IN4")
		(22 "In10.Cu" signal "GND3")
		(2 "B.Cu" signal "BOTTOM")
		(9 "F.Adhes" user "F.Adhesive")
		(11 "B.Adhes" user "B.Adhesive")
		(13 "F.Paste" user "Package Geometry/Pastemask Top")
		(15 "B.Paste" user "Package Geometry/Pastemask Bottom")
		(5 "F.SilkS" user "Ref Des/Silkscreen Top")
		(7 "B.SilkS" user "Ref Des/Silkscreen Bottom")
		(1 "F.Mask" user "Board Geometry/Soldermask Top")
		(3 "B.Mask" user "Board Geometry/Soldermask Bottom")
		(17 "Dwgs.User" user "User.Drawings")
		(19 "Cmts.User" user "User.Comments")
		(21 "Eco1.User" user "User.Eco1")
		(23 "Eco2.User" user "User.Eco2")
		(25 "Edge.Cuts" user "Board Geometry/Outline")
		(27 "Margin" user)
		(31 "F.CrtYd" user "Package Geometry/Place Bound Top")
		(29 "B.CrtYd" user "Package Geometry/Place Bound Bottom")
		(35 "F.Fab" user "Ref Des/Assembly Top")
		(33 "B.Fab" user "Ref Des/Assembly Bottom")
	)
	(footprint ""
		(layer "B.Cu")
		(at 58.890662 -70.063614)
		(property "Reference" "R798"
			(at 0 0 0)
			(layer "B.SilkS")
			(hide yes)
			(effects
				(font
					(size 1.27 1.27)
				)
				(justify mirror)
			)
		)
		(property "Value" ""
			(at 0 0 0)
			(layer "B.Fab")
			(effects
				(font
					(size 1.27 1.27)
				)
				(justify mirror)
			)
		)
		(duplicate_pad_numbers_are_jumpers no)
		(fp_line
			(start -0.7874 -0.4064)
			(end -0.7874 0.4064)
			(stroke
				(width 0.1524)
				(type default)
			)
			(layer "B.SilkS")
		)
		(fp_line
			(start -0.7874 0.4064)
			(end 0.7874 0.4064)
			(stroke
				(width 0.1524)
				(type default)
			)
			(layer "B.SilkS")
		)
		(fp_line
			(start 0.7874 -0.4064)
			(end -0.7874 -0.4064)
			(stroke
				(width 0.1524)
				(type default)
			)
			(layer "B.SilkS")
		)
		(fp_line
			(start 0.7874 0.4064)
			(end 0.7874 -0.4064)
			(stroke
				(width 0.1524)
				(type default)
			)
			(layer "B.SilkS")
		)
		(fp_line
			(start -0.67945 -0.3048)
			(end -0.67945 0.3048)
			(stroke
				(width 0.1)
				(type default)
			)
			(layer "B.Fab")
		)
		(fp_line
			(start -0.67945 0.3048)
			(end -0.120396 0.3048)
			(stroke
				(width 0.1)
				(type default)
			)
			(layer "B.Fab")
		)
		(fp_line
			(start -0.12065 -0.3048)
			(end -0.67945 -0.3048)
			(stroke
				(width 0.1)
				(type default)
			)
			(layer "B.Fab")
		)
		(fp_line
			(start -0.12065 -0.2794)
			(end -0.12065 -0.3048)
			(stroke
				(width 0.1)
				(type default)
			)
			(layer "B.Fab")
		)
		(fp_line
			(start -0.120396 0.2794)
			(end 0.12065 0.2794)
			(stroke
				(width 0.1)
				(type default)
			)
			(layer "B.Fab")
		)
		(fp_line
			(start -0.120396 0.3048)
			(end -0.120396 0.2794)
			(stroke
				(width 0.1)
				(type default)
			)
			(layer "B.Fab")
		)
		(fp_line
			(start 0.12065 -0.305054)
			(end 0.12065 -0.2794)
			(stroke
				(width 0.1)
				(type default)
			)
			(layer "B.Fab")
		)
		(fp_line
			(start 0.12065 -0.2794)
			(end -0.12065 -0.2794)
			(stroke
				(width 0.1)
				(type default)
			)
			(layer "B.Fab")
		)
		(fp_line
			(start 0.12065 0.2794)
			(end 0.12065 0.3048)
			(stroke
				(width 0.1)
				(type default)
			)
			(layer "B.Fab")
		)
		(fp_line
			(start 0.12065 0.3048)
			(end 0.67945 0.3048)
			(stroke
				(width 0.1)
				(type default)
			)
			(layer "B.Fab")
		)
		(fp_line
			(start 0.67945 -0.305054)
			(end 0.12065 -0.305054)
			(stroke
				(width 0.1)
				(type default)
			)
			(layer "B.Fab")
		)
		(fp_line
			(start 0.67945 0.3048)
			(end 0.67945 -0.305054)
			(stroke
				(width 0.1)
				(type default)
			)
			(layer "B.Fab")
		)
		(pad "1" smd circle
			(at 0.40005 0 180)
			(size 0 0)
			(layers "B.Cu" "B.Mask" "B.Paste")
			(net "PGPPA_BMC_AUX_SENSOR")
		)
		(pad "2" smd circle
			(at -0.40005 0 180)
			(size 0 0)
			(layers "B.Cu" "B.Mask" "B.Paste")
			(net "GND")
		)
	)
	(footprint ""
		(layer "B.Cu")
		(at 81.129886 -40.990012)
		(property "Reference" "R344"
			(at 0 0 0)
			(layer "B.SilkS")
			(hide yes)
			(effects
				(font
					(size 1.27 1.27)
				)
				(justify mirror)
			)
		)
		(property "Value" ""
			(at 0 0 0)
			(layer "B.Fab")
			(effects
				(font
					(size 1.27 1.27)
				)
				(justify mirror)
			)
		)
		(duplicate_pad_numbers_are_jumpers no)
		(fp_line
			(start -0.7874 -0.4064)
			(end -0.7874 0.4064)
			(stroke
				(width 0.1524)
				(type default)
			)
			(layer "B.SilkS")
		)
		(fp_line
			(start -0.7874 0.4064)
			(end 0.7874 0.4064)
			(stroke
				(width 0.1524)
				(type default)
			)
			(layer "B.SilkS")
		)
		(fp_line
			(start 0.7874 -0.4064)
			(end -0.7874 -0.4064)
			(stroke
				(width 0.1524)
				(type default)
			)
			(layer "B.SilkS")
		)
		(fp_line
			(start 0.7874 0.4064)
			(end 0.7874 -0.4064)
			(stroke
				(width 0.1524)
				(type default)
			)
			(layer "B.SilkS")
		)
		(fp_line
			(start -0.67945 -0.3048)
			(end -0.67945 0.3048)
			(stroke
				(width 0.1)
				(type default)
			)
			(layer "B.Fab")
		)
		(fp_line
			(start -0.67945 0.3048)
			(end -0.120396 0.3048)
			(stroke
				(width 0.1)
				(type default)
			)
			(layer "B.Fab")
		)
		(fp_line
			(start -0.12065 -0.3048)
			(end -0.67945 -0.3048)
			(stroke
				(width 0.1)
				(type default)
			)
			(layer "B.Fab")
		)
		(fp_line
			(start -0.12065 -0.2794)
			(end -0.12065 -0.3048)
			(stroke
				(width 0.1)
				(type default)
			)
			(layer "B.Fab")
		)
		(fp_line
			(start -0.120396 0.2794)
			(end 0.12065 0.2794)
			(stroke
				(width 0.1)
				(type default)
			)
			(layer "B.Fab")
		)
		(fp_line
			(start -0.120396 0.3048)
			(end -0.120396 0.2794)
			(stroke
				(width 0.1)
				(type default)
			)
			(layer "B.Fab")
		)
		(fp_line
			(start 0.12065 -0.305054)
			(end 0.12065 -0.2794)
			(stroke
				(width 0.1)
				(type default)
			)
			(layer "B.Fab")
		)
		(fp_line
			(start 0.12065 -0.2794)
			(end -0.12065 -0.2794)
			(stroke
				(width 0.1)
				(type default)
			)
			(layer "B.Fab")
		)
		(fp_line
			(start 0.12065 0.2794)
			(end 0.12065 0.3048)
			(stroke
				(width 0.1)
				(type default)
			)
			(layer "B.Fab")
		)
		(fp_line
			(start 0.12065 0.3048)
			(end 0.67945 0.3048)
			(stroke
				(width 0.1)
				(type default)
			)
			(layer "B.Fab")
		)
		(fp_line
			(start 0.67945 -0.305054)
			(end 0.12065 -0.305054)
			(stroke
				(width 0.1)
				(type default)
			)
			(layer "B.Fab")
		)
		(fp_line
			(start 0.67945 0.3048)
			(end 0.67945 -0.305054)
			(stroke
				(width 0.1)
				(type default)
			)
			(layer "B.Fab")
		)
		(pad "1" smd circle
			(at 0.40005 0 180)
			(size 0 0)
			(layers "B.Cu" "B.Mask" "B.Paste")
			(net "GND")
		)
		(pad "2" smd circle
			(at -0.40005 0 180)
			(size 0 0)
			(layers "B.Cu" "B.Mask" "B.Paste")
			(net "M_BMC_DDR4_MACT_N")
		)
	)
	(footprint ""
		(layer "B.Cu")
		(at 60.099702 -43.630342 180)
		(property "Reference" "C59"
			(at 0 0 0)
			(layer "B.SilkS")
			(hide yes)
			(effects
				(font
					(size 1.27 1.27)
				)
				(justify mirror)
			)
		)
		(property "Value" ""
			(at 0 0 0)
			(layer "B.Fab")
			(effects
				(font
					(size 1.27 1.27)
				)
				(justify mirror)
			)
		)
		(duplicate_pad_numbers_are_jumpers no)
		(fp_line
			(start 0.7874 0.4064)
			(end 0.7874 -0.4064)
			(stroke
				(width 0.1524)
				(type default)
			)
			(layer "B.SilkS")
		)
		(fp_line
			(start 0.7874 -0.4064)
			(end -0.7874 -0.4064)
			(stroke
				(width 0.1524)
				(type default)
			)
			(layer "B.SilkS")
		)
		(fp_line
			(start -0.7874 0.4064)
			(end 0.7874 0.4064)
			(stroke
				(width 0.1524)
				(type default)
			)
			(layer "B.SilkS")
		)
		(fp_line
			(start -0.7874 -0.4064)
			(end -0.7874 0.4064)
			(stroke
				(width 0.1524)
				(type default)
			)
			(layer "B.SilkS")
		)
		(fp_line
			(start 0.67945 0.3048)
			(end 0.67945 -0.305054)
			(stroke
				(width 0.1)
				(type default)
			)
			(layer "B.Fab")
		)
		(fp_line
			(start 0.67945 -0.305054)
			(end 0.12065 -0.305054)
			(stroke
				(width 0.1)
				(type default)
			)
			(layer "B.Fab")
		)
		(fp_line
			(start 0.12065 0.3048)
			(end 0.67945 0.3048)
			(stroke
				(width 0.1)
				(type default)
			)
			(layer "B.Fab")
		)
		(fp_line
			(start 0.12065 0.2794)
			(end 0.12065 0.3048)
			(stroke
				(width 0.1)
				(type default)
			)
			(layer "B.Fab")
		)
		(fp_line
			(start 0.12065 -0.2794)
			(end -0.12065 -0.2794)
			(stroke
				(width 0.1)
				(type default)
			)
			(layer "B.Fab")
		)
		(fp_line
			(start 0.12065 -0.305054)
			(end 0.12065 -0.2794)
			(stroke
				(width 0.1)
				(type default)
			)
			(layer "B.Fab")
		)
		(fp_line
			(start -0.120396 0.3048)
			(end -0.120396 0.2794)
			(stroke
				(width 0.1)
				(type default)
			)
			(layer "B.Fab")
		)
		(fp_line
			(start -0.120396 0.2794)
			(end 0.12065 0.2794)
			(stroke
				(width 0.1)
				(type default)
			)
			(layer "B.Fab")
		)
		(fp_line
			(start -0.12065 -0.2794)
			(end -0.12065 -0.3048)
			(stroke
				(width 0.1)
				(type default)
			)
			(layer "B.Fab")
		)
		(fp_line
			(start -0.12065 -0.3048)
			(end -0.67945 -0.3048)
			(stroke
				(width 0.1)
				(type default)
			)
			(layer "B.Fab")
		)
		(fp_line
			(start -0.67945 0.3048)
			(end -0.120396 0.3048)
			(stroke
				(width 0.1)
				(type default)
			)
			(layer "B.Fab")
		)
		(fp_line
			(start -0.67945 -0.3048)
			(end -0.67945 0.3048)
			(stroke
				(width 0.1)
				(type default)
			)
			(layer "B.Fab")
		)
		(pad "1" smd circle
			(at 0.40005 0)
			(size 0 0)
			(layers "B.Cu" "B.Mask" "B.Paste")
			(net "P1V0_STBY_PLAVDD")
		)
		(pad "2" smd circle
			(at -0.40005 0)
			(size 0 0)
			(layers "B.Cu" "B.Mask" "B.Paste")
			(net "GND")
		)
	)
	(footprint ""
		(layer "B.Cu")
		(at 37.4015 -103.632)
		(property "Reference" "C146"
			(at 0 0 0)
			(layer "B.SilkS")
			(hide yes)
			(effects
				(font
					(size 1.27 1.27)
				)
				(justify mirror)
			)
		)
		(property "Value" ""
			(at 0 0 0)
			(layer "B.Fab")
			(effects
				(font
					(size 1.27 1.27)
				)
				(justify mirror)
			)
		)
		(duplicate_pad_numbers_are_jumpers no)
		(fp_line
			(start -0.7874 -0.4064)
			(end -0.7874 0.4064)
			(stroke
				(width 0.1524)
				(type default)
			)
			(layer "B.SilkS")
		)
		(fp_line
			(start -0.7874 0.4064)
			(end 0.7874 0.4064)
			(stroke
				(width 0.1524)
				(type default)
			)
			(layer "B.SilkS")
		)
		(fp_line
			(start 0.7874 -0.4064)
			(end -0.7874 -0.4064)
			(stroke
				(width 0.1524)
				(type default)
			)
			(layer "B.SilkS")
		)
		(fp_line
			(start 0.7874 0.4064)
			(end 0.7874 -0.4064)
			(stroke
				(width 0.1524)
				(type default)
			)
			(layer "B.SilkS")
		)
		(fp_line
			(start -0.67945 -0.3048)
			(end -0.67945 0.3048)
			(stroke
				(width 0.1)
				(type default)
			)
			(layer "B.Fab")
		)
		(fp_line
			(start -0.67945 0.3048)
			(end -0.120396 0.3048)
			(stroke
				(width 0.1)
				(type default)
			)
			(layer "B.Fab")
		)
		(fp_line
			(start -0.12065 -0.3048)
			(end -0.67945 -0.3048)
			(stroke
				(width 0.1)
				(type default)
			)
			(layer "B.Fab")
		)
		(fp_line
			(start -0.12065 -0.2794)
			(end -0.12065 -0.3048)
			(stroke
				(width 0.1)
				(type default)
			)
			(layer "B.Fab")
		)
		(fp_line
			(start -0.120396 0.2794)
			(end 0.12065 0.2794)
			(stroke
				(width 0.1)
				(type default)
			)
			(layer "B.Fab")
		)
		(fp_line
			(start -0.120396 0.3048)
			(end -0.120396 0.2794)
			(stroke
				(width 0.1)
				(type default)
			)
			(layer "B.Fab")
		)
		(fp_line
			(start 0.12065 -0.305054)
			(end 0.12065 -0.2794)
			(stroke
				(width 0.1)
				(type default)
			)
			(layer "B.Fab")
		)
		(fp_line
			(start 0.12065 -0.2794)
			(end -0.12065 -0.2794)
			(stroke
				(width 0.1)
				(type default)
			)
			(layer "B.Fab")
		)
		(fp_line
			(start 0.12065 0.2794)
			(end 0.12065 0.3048)
			(stroke
				(width 0.1)
				(type default)
			)
			(layer "B.Fab")
		)
		(fp_line
			(start 0.12065 0.3048)
			(end 0.67945 0.3048)
			(stroke
				(width 0.1)
				(type default)
			)
			(layer "B.Fab")
		)
		(fp_line
			(start 0.67945 -0.305054)
			(end 0.12065 -0.305054)
			(stroke
				(width 0.1)
				(type default)
			)
			(layer "B.Fab")
		)
		(fp_line
			(start 0.67945 0.3048)
			(end 0.67945 -0.305054)
			(stroke
				(width 0.1)
				(type default)
			)
			(layer "B.Fab")
		)
		(pad "1" smd circle
			(at 0.40005 0 180)
			(size 0 0)
			(layers "B.Cu" "B.Mask" "B.Paste")
			(net "P3V3_AUX")
		)
		(pad "2" smd circle
			(at -0.40005 0 180)
			(size 0 0)
			(layers "B.Cu" "B.Mask" "B.Paste")
			(net "GND")
		)
	)
	(footprint ""
		(layer "B.Cu")
		(at 57.673494 -44.412662 -90)
		(property "Reference" "C64"
			(at 0 0 90)
			(layer "B.SilkS")
			(hide yes)
			(effects
				(font
					(size 1.27 1.27)
				)
				(justify mirror)
			)
		)
		(property "Value" ""
			(at 0 0 90)
			(layer "B.Fab")
			(effects
				(font
					(size 1.27 1.27)
				)
				(justify mirror)
			)
		)
		(duplicate_pad_numbers_are_jumpers no)
		(fp_line
			(start -0.7874 0.4064)
			(end 0.7874 0.4064)
			(stroke
				(width 0.1524)
				(type default)
			)
			(layer "B.SilkS")
		)
		(fp_line
			(start 0.7874 0.4064)
			(end 0.7874 -0.4064)
			(stroke
				(width 0.1524)
				(type default)
			)
			(layer "B.SilkS")
		)
		(fp_line
			(start -0.7874 -0.4064)
			(end -0.7874 0.4064)
			(stroke
				(width 0.1524)
				(type default)
			)
			(layer "B.SilkS")
		)
		(fp_line
			(start 0.7874 -0.4064)
			(end -0.7874 -0.4064)
			(stroke
				(width 0.1524)
				(type default)
			)
			(layer "B.SilkS")
		)
		(fp_line
			(start -0.67945 0.3048)
			(end -0.120396 0.3048)
			(stroke
				(width 0.1)
				(type default)
			)
			(layer "B.Fab")
		)
		(fp_line
			(start -0.120396 0.3048)
			(end -0.120396 0.2794)
			(stroke
				(width 0.1)
				(type default)
			)
			(layer "B.Fab")
		)
		(fp_line
			(start 0.12065 0.3048)
			(end 0.67945 0.3048)
			(stroke
				(width 0.1)
				(type default)
			)
			(layer "B.Fab")
		)
		(fp_line
			(start 0.67945 0.3048)
			(end 0.67945 -0.305054)
			(stroke
				(width 0.1)
				(type default)
			)
			(layer "B.Fab")
		)
		(fp_line
			(start -0.120396 0.2794)
			(end 0.12065 0.2794)
			(stroke
				(width 0.1)
				(type default)
			)
			(layer "B.Fab")
		)
		(fp_line
			(start 0.12065 0.2794)
			(end 0.12065 0.3048)
			(stroke
				(width 0.1)
				(type default)
			)
			(layer "B.Fab")
		)
		(fp_line
			(start -0.12065 -0.2794)
			(end -0.12065 -0.3048)
			(stroke
				(width 0.1)
				(type default)
			)
			(layer "B.Fab")
		)
		(fp_line
			(start 0.12065 -0.2794)
			(end -0.12065 -0.2794)
			(stroke
				(width 0.1)
				(type default)
			)
			(layer "B.Fab")
		)
		(fp_line
			(start -0.67945 -0.3048)
			(end -0.67945 0.3048)
			(stroke
				(width 0.1)
				(type default)
			)
			(layer "B.Fab")
		)
		(fp_line
			(start -0.12065 -0.3048)
			(end -0.67945 -0.3048)
			(stroke
				(width 0.1)
				(type default)
			)
			(layer "B.Fab")
		)
		(fp_line
			(start 0.12065 -0.305054)
			(end 0.12065 -0.2794)
			(stroke
				(width 0.1)
				(type default)
			)
			(layer "B.Fab")
		)
		(fp_line
			(start 0.67945 -0.305054)
			(end 0.12065 -0.305054)
			(stroke
				(width 0.1)
				(type default)
			)
			(layer "B.Fab")
		)
		(pad "1" smd circle
			(at 0.40005 0 90)
			(size 0 0)
			(layers "B.Cu" "B.Mask" "B.Paste")
			(net "P1V0_STBY_PLAVDD")
		)
		(pad "2" smd circle
			(at -0.40005 0 90)
			(size 0 0)
			(layers "B.Cu" "B.Mask" "B.Paste")
			(net "GND")
		)
	)
	(footprint ""
		(layer "B.Cu")
		(at 31.877 -30.353 -90)
		(property "Reference" "C209"
			(at 0 0 90)
			(layer "B.SilkS")
			(hide yes)
			(effects
				(font
					(size 1.27 1.27)
				)
				(justify mirror)
			)
		)
		(property "Value" ""
			(at 0 0 90)
			(layer "B.Fab")
			(effects
				(font
					(size 1.27 1.27)
				)
				(justify mirror)
			)
		)
		(duplicate_pad_numbers_are_jumpers no)
		(fp_line
			(start -0.7874 0.4064)
			(end 0.7874 0.4064)
			(stroke
				(width 0.1524)
				(type default)
			)
			(layer "B.SilkS")
		)
		(fp_line
			(start 0.7874 0.4064)
			(end 0.7874 -0.4064)
			(stroke
				(width 0.1524)
				(type default)
			)
			(layer "B.SilkS")
		)
		(fp_line
			(start -0.7874 -0.4064)
			(end -0.7874 0.4064)
			(stroke
				(width 0.1524)
				(type default)
			)
			(layer "B.SilkS")
		)
		(fp_line
			(start 0.7874 -0.4064)
			(end -0.7874 -0.4064)
			(stroke
				(width 0.1524)
				(type default)
			)
			(layer "B.SilkS")
		)
		(fp_line
			(start -0.67945 0.3048)
			(end -0.120396 0.3048)
			(stroke
				(width 0.1)
				(type default)
			)
			(layer "B.Fab")
		)
		(fp_line
			(start -0.120396 0.3048)
			(end -0.120396 0.2794)
			(stroke
				(width 0.1)
				(type default)
			)
			(layer "B.Fab")
		)
		(fp_line
			(start 0.12065 0.3048)
			(end 0.67945 0.3048)
			(stroke
				(width 0.1)
				(type default)
			)
			(layer "B.Fab")
		)
		(fp_line
			(start 0.67945 0.3048)
			(end 0.67945 -0.305054)
			(stroke
				(width 0.1)
				(type default)
			)
			(layer "B.Fab")
		)
		(fp_line
			(start -0.120396 0.2794)
			(end 0.12065 0.2794)
			(stroke
				(width 0.1)
				(type default)
			)
			(layer "B.Fab")
		)
		(fp_line
			(start 0.12065 0.2794)
			(end 0.12065 0.3048)
			(stroke
				(width 0.1)
				(type default)
			)
			(layer "B.Fab")
		)
		(fp_line
			(start -0.12065 -0.2794)
			(end -0.12065 -0.3048)
			(stroke
				(width 0.1)
				(type default)
			)
			(layer "B.Fab")
		)
		(fp_line
			(start 0.12065 -0.2794)
			(end -0.12065 -0.2794)
			(stroke
				(width 0.1)
				(type default)
			)
			(layer "B.Fab")
		)
		(fp_line
			(start -0.67945 -0.3048)
			(end -0.67945 0.3048)
			(stroke
				(width 0.1)
				(type default)
			)
			(layer "B.Fab")
		)
		(fp_line
			(start -0.12065 -0.3048)
			(end -0.67945 -0.3048)
			(stroke
				(width 0.1)
				(type default)
			)
			(layer "B.Fab")
		)
		(fp_line
			(start 0.12065 -0.305054)
			(end 0.12065 -0.2794)
			(stroke
				(width 0.1)
				(type default)
			)
			(layer "B.Fab")
		)
		(fp_line
			(start 0.67945 -0.305054)
			(end 0.12065 -0.305054)
			(stroke
				(width 0.1)
				(type default)
			)
			(layer "B.Fab")
		)
		(pad "1" smd circle
			(at 0.40005 0 90)
			(size 0 0)
			(layers "B.Cu" "B.Mask" "B.Paste")
			(net "V_DACG_IO")
		)
		(pad "2" smd circle
			(at -0.40005 0 90)
			(size 0 0)
			(layers "B.Cu" "B.Mask" "B.Paste")
			(net "GND")
		)
	)
)
